(kicad_pcb
	(version 20260206)
	(generator "pcbnew")
	(generator_version "10.0")
	(general
		(thickness 1.6)
		(legacy_teardrops no)
	)
	(paper "A4")
	(title_block
		(title "01162023_DA0F0TEBIF0_F0T_Expander_BD_F_brd_V02_OCP.brd")
		(comment 1 "Grand Teton / footprints 6253-6259 of 9728")
	)
	(layers
		(0 "F.Cu" signal "TOP")
		(4 "In1.Cu" signal "GND")
		(6 "In2.Cu" signal "VCC")
		(8 "In3.Cu" signal "VCC1")
		(10 "In4.Cu" signal "GND1")
		(12 "In5.Cu" signal "IN1")
		(14 "In6.Cu" signal "GND2")
		(16 "In7.Cu" signal "IN2")
		(18 "In8.Cu" signal "GND3")
		(20 "In9.Cu" signal "IN3")
		(22 "In10.Cu" signal "GND4")
		(24 "In11.Cu" signal "IN4")
		(26 "In12.Cu" signal "GND5")
		(28 "In13.Cu" signal "IN5")
		(30 "In14.Cu" signal "GND6")
		(32 "In15.Cu" signal "IN6")
		(34 "In16.Cu" signal "GND7")
		(2 "B.Cu" signal "BOTTOM")
		(9 "F.Adhes" user "F.Adhesive")
		(11 "B.Adhes" user "B.Adhesive")
		(13 "F.Paste" user "Package Geometry/Pastemask Top")
		(15 "B.Paste" user "Package Geometry/Pastemask Bottom")
		(5 "F.SilkS" user "Ref Des/Silkscreen Top")
		(7 "B.SilkS" user "Ref Des/Silkscreen Bottom")
		(1 "F.Mask" user "Board Geometry/Soldermask Top")
		(3 "B.Mask" user "Board Geometry/Soldermask Bottom")
		(17 "Dwgs.User" user "User.Drawings")
		(19 "Cmts.User" user "User.Comments")
		(21 "Eco1.User" user "User.Eco1")
		(23 "Eco2.User" user "User.Eco2")
		(25 "Edge.Cuts" user "Board Geometry/Outline")
		(27 "Margin" user)
		(31 "F.CrtYd" user "Package Geometry/Place Bound Top")
		(29 "B.CrtYd" user "Package Geometry/Place Bound Bottom")
		(35 "F.Fab" user "Ref Des/Assembly Top")
		(33 "B.Fab" user "Ref Des/Assembly Bottom")
	)
	(footprint ""
		(layer "F.Cu")
		(at 190.061088 -37.951156)
		(property "Reference" "Q223"
			(at -0.018288 -1.925574 0)
			(unlocked yes)
			(layer "F.SilkS")
			(effects
				(font
					(size 0.7874 0.5842)
					(thickness 0.1524)
				)
			)
		)
		(property "Value" ""
			(at 0 0 0)
			(layer "F.Fab")
			(effects
				(font
					(size 1.27 1.27)
				)
			)
		)
		(duplicate_pad_numbers_are_jumpers no)
		(fp_line
			(start -1.376172 -1.199896)
			(end -0.508 -1.199896)
			(stroke
				(width 0.1524)
				(type default)
			)
			(layer "F.SilkS")
		)
		(fp_line
			(start -1.376172 1.199896)
			(end -1.376172 -1.199896)
			(stroke
				(width 0.1524)
				(type default)
			)
			(layer "F.SilkS")
		)
		(fp_line
			(start -0.508 -1.199896)
			(end 0 -0.762)
			(stroke
				(width 0.1524)
				(type default)
			)
			(layer "F.SilkS")
		)
		(fp_line
			(start 0 -0.762)
			(end 0.508 -1.199896)
			(stroke
				(width 0.1524)
				(type default)
			)
			(layer "F.SilkS")
		)
		(fp_line
			(start 0.508 -1.199896)
			(end 1.376172 -1.199896)
			(stroke
				(width 0.1524)
				(type default)
			)
			(layer "F.SilkS")
		)
		(fp_line
			(start 1.376172 -1.199896)
			(end 1.376172 1.199896)
			(stroke
				(width 0.1524)
				(type default)
			)
			(layer "F.SilkS")
		)
		(fp_line
			(start 1.376172 1.199896)
			(end -1.376172 1.199896)
			(stroke
				(width 0.1524)
				(type default)
			)
			(layer "F.SilkS")
		)
		(fp_poly
			(pts
				(xy -1.500886 -1.23571) (xy -1.77038 -2.043938) (xy -2.309114 -1.50495)
			)
			(stroke
				(width 0)
				(type default)
			)
			(fill yes)
			(layer "F.SilkS")
		)
		(fp_line
			(start -0.674878 -1.100074)
			(end 0.674878 -1.100074)
			(stroke
				(width 0.1)
				(type default)
			)
			(layer "F.Fab")
		)
		(fp_line
			(start -0.674878 1.100074)
			(end -0.674878 -1.100074)
			(stroke
				(width 0.1)
				(type default)
			)
			(layer "F.Fab")
		)
		(fp_line
			(start 0.674878 -1.100074)
			(end 0.674878 1.100074)
			(stroke
				(width 0.1)
				(type default)
			)
			(layer "F.Fab")
		)
		(fp_line
			(start 0.674878 1.100074)
			(end -0.674878 1.100074)
			(stroke
				(width 0.1)
				(type default)
			)
			(layer "F.Fab")
		)
		(fp_poly
			(pts
				(xy -1.4605 -0.7493) (xy -2.2225 -1.1303) (xy -2.2225 -0.3683)
			)
			(stroke
				(width 0)
				(type default)
			)
			(fill yes)
			(layer "F.Fab")
		)
		(pad "1" smd rect
			(at -0.899922 -0.750062 270)
			(size 0.6096 0.6096)
			(layers "F.Cu" "F.Mask" "F.Paste")
			(net "GND")
		)
		(pad "2" smd rect
			(at -0.899922 0 270)
			(size 0.4064 0.6096)
			(layers "F.Cu" "F.Mask" "F.Paste")
			(net "P3V3_SSD7_PG_G1")
		)
		(pad "3" smd rect
			(at -0.899922 0.750062 270)
			(size 0.6096 0.6096)
			(layers "F.Cu" "F.Mask" "F.Paste")
			(net "PWRGD_P3V3_SSD7_D")
		)
		(pad "4" smd rect
			(at 0.899922 0.750062 270)
			(size 0.6096 0.6096)
			(layers "F.Cu" "F.Mask" "F.Paste")
			(net "GND")
		)
		(pad "5" smd rect
			(at 0.899922 0 270)
			(size 0.4064 0.6096)
			(layers "F.Cu" "F.Mask" "F.Paste")
			(net "P3V3_SSD7_PG_G2")
		)
		(pad "6" smd rect
			(at 0.899922 -0.750062 270)
			(size 0.6096 0.6096)
			(layers "F.Cu" "F.Mask" "F.Paste")
			(net "P3V3_SSD7_PG_G2")
		)
	)
	(footprint ""
		(layer "F.Cu")
		(at 145.643854 -311.725564 45)
		(property "Reference" "R1283"
			(at 0 0 45)
			(layer "F.SilkS")
			(hide yes)
			(effects
				(font
					(size 1.27 1.27)
				)
			)
		)
		(property "Value" ""
			(at 0 0 45)
			(layer "F.Fab")
			(effects
				(font
					(size 1.27 1.27)
				)
			)
		)
		(duplicate_pad_numbers_are_jumpers no)
		(fp_line
			(start -0.787389 -0.406267)
			(end 0.787389 -0.406267)
			(stroke
				(width 0.1524)
				(type default)
			)
			(layer "F.SilkS")
		)
		(fp_line
			(start -0.787389 0.406267)
			(end -0.787389 -0.406267)
			(stroke
				(width 0.1524)
				(type default)
			)
			(layer "F.SilkS")
		)
		(fp_line
			(start 0.787389 -0.406267)
			(end 0.787389 0.406267)
			(stroke
				(width 0.1524)
				(type default)
			)
			(layer "F.SilkS")
		)
		(fp_line
			(start 0.787389 0.406267)
			(end -0.787389 0.406267)
			(stroke
				(width 0.1524)
				(type default)
			)
			(layer "F.SilkS")
		)
		(fp_line
			(start -0.679446 -0.305149)
			(end -0.120695 -0.304969)
			(stroke
				(width 0.1)
				(type default)
			)
			(layer "F.Fab")
		)
		(fp_line
			(start -0.120695 -0.304969)
			(end -0.120695 -0.279466)
			(stroke
				(width 0.1)
				(type default)
			)
			(layer "F.Fab")
		)
		(fp_line
			(start -0.120695 -0.279466)
			(end 0.120695 -0.279466)
			(stroke
				(width 0.1)
				(type default)
			)
			(layer "F.Fab")
		)
		(fp_line
			(start -0.679446 0.30479)
			(end -0.679446 -0.305149)
			(stroke
				(width 0.1)
				(type default)
			)
			(layer "F.Fab")
		)
		(fp_line
			(start 0.120515 -0.30479)
			(end 0.679446 -0.30479)
			(stroke
				(width 0.1)
				(type default)
			)
			(layer "F.Fab")
		)
		(fp_line
			(start 0.120695 -0.279466)
			(end 0.120515 -0.30479)
			(stroke
				(width 0.1)
				(type default)
			)
			(layer "F.Fab")
		)
		(fp_line
			(start -0.120695 0.279466)
			(end -0.120515 0.30479)
			(stroke
				(width 0.1)
				(type default)
			)
			(layer "F.Fab")
		)
		(fp_line
			(start -0.120515 0.30479)
			(end -0.679446 0.30479)
			(stroke
				(width 0.1)
				(type default)
			)
			(layer "F.Fab")
		)
		(fp_line
			(start 0.679446 -0.30479)
			(end 0.679446 0.30479)
			(stroke
				(width 0.1)
				(type default)
			)
			(layer "F.Fab")
		)
		(fp_line
			(start 0.120335 0.279466)
			(end -0.120695 0.279466)
			(stroke
				(width 0.1)
				(type default)
			)
			(layer "F.Fab")
		)
		(fp_line
			(start 0.120515 0.30479)
			(end 0.120335 0.279466)
			(stroke
				(width 0.1)
				(type default)
			)
			(layer "F.Fab")
		)
		(fp_line
			(start 0.679446 0.30479)
			(end 0.120515 0.30479)
			(stroke
				(width 0.1)
				(type default)
			)
			(layer "F.Fab")
		)
		(pad "1" smd circle
			(at -0.40005 0 45)
			(size 0 0)
			(layers "F.Cu" "F.Mask" "F.Paste")
			(net "GND")
		)
		(pad "2" smd circle
			(at 0.40005 0 45)
			(size 0 0)
			(layers "F.Cu" "F.Mask" "F.Paste")
			(net "PEX1_DBG_SEL1")
		)
	)
	(footprint ""
		(layer "F.Cu")
		(at 7.613396 -138.360404 180)
		(property "Reference" "R4442"
			(at 0 0 180)
			(layer "F.SilkS")
			(hide yes)
			(effects
				(font
					(size 1.27 1.27)
				)
			)
		)
		(property "Value" ""
			(at 0 0 180)
			(layer "F.Fab")
			(effects
				(font
					(size 1.27 1.27)
				)
			)
		)
		(duplicate_pad_numbers_are_jumpers no)
		(fp_line
			(start 0.7874 0.4064)
			(end -0.7874 0.4064)
			(stroke
				(width 0.1524)
				(type default)
			)
			(layer "F.SilkS")
		)
		(fp_line
			(start 0.7874 -0.4064)
			(end 0.7874 0.4064)
			(stroke
				(width 0.1524)
				(type default)
			)
			(layer "F.SilkS")
		)
		(fp_line
			(start -0.7874 0.4064)
			(end -0.7874 -0.4064)
			(stroke
				(width 0.1524)
				(type default)
			)
			(layer "F.SilkS")
		)
		(fp_line
			(start -0.7874 -0.4064)
			(end 0.7874 -0.4064)
			(stroke
				(width 0.1524)
				(type default)
			)
			(layer "F.SilkS")
		)
		(fp_line
			(start 0.67945 0.3048)
			(end 0.120396 0.3048)
			(stroke
				(width 0.1)
				(type default)
			)
			(layer "F.Fab")
		)
		(fp_line
			(start 0.67945 -0.3048)
			(end 0.67945 0.3048)
			(stroke
				(width 0.1)
				(type default)
			)
			(layer "F.Fab")
		)
		(fp_line
			(start 0.12065 -0.2794)
			(end 0.12065 -0.3048)
			(stroke
				(width 0.1)
				(type default)
			)
			(layer "F.Fab")
		)
		(fp_line
			(start 0.12065 -0.3048)
			(end 0.67945 -0.3048)
			(stroke
				(width 0.1)
				(type default)
			)
			(layer "F.Fab")
		)
		(fp_line
			(start 0.120396 0.3048)
			(end 0.120396 0.2794)
			(stroke
				(width 0.1)
				(type default)
			)
			(layer "F.Fab")
		)
		(fp_line
			(start 0.120396 0.2794)
			(end -0.12065 0.2794)
			(stroke
				(width 0.1)
				(type default)
			)
			(layer "F.Fab")
		)
		(fp_line
			(start -0.12065 0.3048)
			(end -0.67945 0.3048)
			(stroke
				(width 0.1)
				(type default)
			)
			(layer "F.Fab")
		)
		(fp_line
			(start -0.12065 0.2794)
			(end -0.12065 0.3048)
			(stroke
				(width 0.1)
				(type default)
			)
			(layer "F.Fab")
		)
		(fp_line
			(start -0.12065 -0.2794)
			(end 0.12065 -0.2794)
			(stroke
				(width 0.1)
				(type default)
			)
			(layer "F.Fab")
		)
		(fp_line
			(start -0.12065 -0.305054)
			(end -0.12065 -0.2794)
			(stroke
				(width 0.1)
				(type default)
			)
			(layer "F.Fab")
		)
		(fp_line
			(start -0.67945 0.3048)
			(end -0.67945 -0.305054)
			(stroke
				(width 0.1)
				(type default)
			)
			(layer "F.Fab")
		)
		(fp_line
			(start -0.67945 -0.305054)
			(end -0.12065 -0.305054)
			(stroke
				(width 0.1)
				(type default)
			)
			(layer "F.Fab")
		)
		(pad "1" smd circle
			(at -0.40005 0 180)
			(size 0 0)
			(layers "F.Cu" "F.Mask" "F.Paste")
			(net "PWRGD_P12V_NIC0")
		)
		(pad "2" smd circle
			(at 0.40005 0 180)
			(size 0 0)
			(layers "F.Cu" "F.Mask" "F.Paste")
			(net "PWRGD_P12V_NIC0_R")
		)
	)
	(footprint ""
		(layer "F.Cu")
		(at 69.926454 -25.432004 -90)
		(property "Reference" "C967"
			(at 0 0 270)
			(layer "F.SilkS")
			(hide yes)
			(effects
				(font
					(size 1.27 1.27)
				)
			)
		)
		(property "Value" ""
			(at 0 0 270)
			(layer "F.Fab")
			(effects
				(font
					(size 1.27 1.27)
				)
			)
		)
		(duplicate_pad_numbers_are_jumpers no)
		(fp_line
			(start -0.7874 0.4064)
			(end -0.7874 -0.4064)
			(stroke
				(width 0.1524)
				(type default)
			)
			(layer "F.SilkS")
		)
		(fp_line
			(start 0.7874 0.4064)
			(end -0.7874 0.4064)
			(stroke
				(width 0.1524)
				(type default)
			)
			(layer "F.SilkS")
		)
		(fp_line
			(start -0.7874 -0.4064)
			(end 0.7874 -0.4064)
			(stroke
				(width 0.1524)
				(type default)
			)
			(layer "F.SilkS")
		)
		(fp_line
			(start 0.7874 -0.4064)
			(end 0.7874 0.4064)
			(stroke
				(width 0.1524)
				(type default)
			)
			(layer "F.SilkS")
		)
		(fp_line
			(start -0.67945 0.3048)
			(end -0.67945 -0.305054)
			(stroke
				(width 0.1)
				(type default)
			)
			(layer "F.Fab")
		)
		(fp_line
			(start -0.12065 0.3048)
			(end -0.67945 0.3048)
			(stroke
				(width 0.1)
				(type default)
			)
			(layer "F.Fab")
		)
		(fp_line
			(start 0.120396 0.3048)
			(end 0.120396 0.2794)
			(stroke
				(width 0.1)
				(type default)
			)
			(layer "F.Fab")
		)
		(fp_line
			(start 0.67945 0.3048)
			(end 0.120396 0.3048)
			(stroke
				(width 0.1)
				(type default)
			)
			(layer "F.Fab")
		)
		(fp_line
			(start -0.12065 0.2794)
			(end -0.12065 0.3048)
			(stroke
				(width 0.1)
				(type default)
			)
			(layer "F.Fab")
		)
		(fp_line
			(start 0.120396 0.2794)
			(end -0.12065 0.2794)
			(stroke
				(width 0.1)
				(type default)
			)
			(layer "F.Fab")
		)
		(fp_line
			(start -0.12065 -0.2794)
			(end 0.12065 -0.2794)
			(stroke
				(width 0.1)
				(type default)
			)
			(layer "F.Fab")
		)
		(fp_line
			(start 0.12065 -0.2794)
			(end 0.12065 -0.3048)
			(stroke
				(width 0.1)
				(type default)
			)
			(layer "F.Fab")
		)
		(fp_line
			(start 0.12065 -0.3048)
			(end 0.67945 -0.3048)
			(stroke
				(width 0.1)
				(type default)
			)
			(layer "F.Fab")
		)
		(fp_line
			(start 0.67945 -0.3048)
			(end 0.67945 0.3048)
			(stroke
				(width 0.1)
				(type default)
			)
			(layer "F.Fab")
		)
		(fp_line
			(start -0.67945 -0.305054)
			(end -0.12065 -0.305054)
			(stroke
				(width 0.1)
				(type default)
			)
			(layer "F.Fab")
		)
		(fp_line
			(start -0.12065 -0.305054)
			(end -0.12065 -0.2794)
			(stroke
				(width 0.1)
				(type default)
			)
			(layer "F.Fab")
		)
		(pad "1" smd circle
			(at -0.40005 0 270)
			(size 0 0)
			(layers "F.Cu" "F.Mask" "F.Paste")
			(net "GND")
		)
		(pad "2" smd circle
			(at 0.40005 0 270)
			(size 0 0)
			(layers "F.Cu" "F.Mask" "F.Paste")
			(net "P3V3_SSD2")
		)
	)
	(footprint ""
		(layer "F.Cu")
		(at 381.40386 -343.952322 90)
		(property "Reference" "C787"
			(at 0 0 90)
			(layer "F.SilkS")
			(hide yes)
			(effects
				(font
					(size 1.27 1.27)
				)
			)
		)
		(property "Value" ""
			(at 0 0 90)
			(layer "F.Fab")
			(effects
				(font
					(size 1.27 1.27)
				)
			)
		)
		(duplicate_pad_numbers_are_jumpers no)
		(fp_line
			(start 0.299974 -0.150114)
			(end 0.299974 0.150114)
			(stroke
				(width 0.1)
				(type default)
			)
			(layer "F.Fab")
		)
		(fp_line
			(start -0.299974 -0.150114)
			(end 0.299974 -0.150114)
			(stroke
				(width 0.1)
				(type default)
			)
			(layer "F.Fab")
		)
		(fp_line
			(start 0.299974 0.150114)
			(end -0.299974 0.150114)
			(stroke
				(width 0.1)
				(type default)
			)
			(layer "F.Fab")
		)
		(fp_line
			(start -0.299974 0.150114)
			(end -0.299974 -0.150114)
			(stroke
				(width 0.1)
				(type default)
			)
			(layer "F.Fab")
		)
		(pad "1" smd rect
			(at -0.2667 0 90)
			(size 0.3048 0.381)
			(layers "F.Cu" "F.Mask" "F.Paste")
			(net "P5E_PEX3_STN6_TX_DN<99>")
		)
		(pad "2" smd rect
			(at 0.2667 0 90)
			(size 0.3048 0.381)
			(layers "F.Cu" "F.Mask" "F.Paste")
			(net "P5E_PEX3_STN6_TX_C_DN<99>")
		)
	)
	(footprint ""
		(layer "F.Cu")
		(at 196.119242 -154.304746 180)
		(property "Reference" "C214"
			(at 0 0 180)
			(layer "F.SilkS")
			(hide yes)
			(effects
				(font
					(size 1.27 1.27)
				)
			)
		)
		(property "Value" ""
			(at 0 0 180)
			(layer "F.Fab")
			(effects
				(font
					(size 1.27 1.27)
				)
			)
		)
		(duplicate_pad_numbers_are_jumpers no)
		(fp_line
			(start 0.299974 0.150114)
			(end -0.299974 0.150114)
			(stroke
				(width 0.1)
				(type default)
			)
			(layer "F.Fab")
		)
		(fp_line
			(start 0.299974 -0.150114)
			(end 0.299974 0.150114)
			(stroke
				(width 0.1)
				(type default)
			)
			(layer "F.Fab")
		)
		(fp_line
			(start -0.299974 0.150114)
			(end -0.299974 -0.150114)
			(stroke
				(width 0.1)
				(type default)
			)
			(layer "F.Fab")
		)
		(fp_line
			(start -0.299974 -0.150114)
			(end 0.299974 -0.150114)
			(stroke
				(width 0.1)
				(type default)
			)
			(layer "F.Fab")
		)
		(pad "1" smd rect
			(at -0.2667 0 180)
			(size 0.3048 0.381)
			(layers "F.Cu" "F.Mask" "F.Paste")
			(net "P5E_PEX1_STN0_TX_DN<14>")
		)
		(pad "2" smd rect
			(at 0.2667 0 180)
			(size 0.3048 0.381)
			(layers "F.Cu" "F.Mask" "F.Paste")
			(net "P5E_PEX1_STN0_TX_C_DN<14>")
		)
	)
	(footprint ""
		(layer "F.Cu")
		(at 228.103684 -257.99796 -90)
		(property "Reference" "R6501"
			(at 0 0 270)
			(layer "F.SilkS")
			(hide yes)
			(effects
				(font
					(size 1.27 1.27)
				)
			)
		)
		(property "Value" ""
			(at 0 0 270)
			(layer "F.Fab")
			(effects
				(font
					(size 1.27 1.27)
				)
			)
		)
		(duplicate_pad_numbers_are_jumpers no)
		(fp_line
			(start -0.7874 0.4064)
			(end -0.7874 -0.4064)
			(stroke
				(width 0.1524)
				(type default)
			)
			(layer "F.SilkS")
		)
		(fp_line
			(start 0.7874 0.4064)
			(end -0.7874 0.4064)
			(stroke
				(width 0.1524)
				(type default)
			)
			(layer "F.SilkS")
		)
		(fp_line
			(start -0.7874 -0.4064)
			(end 0.7874 -0.4064)
			(stroke
				(width 0.1524)
				(type default)
			)
			(layer "F.SilkS")
		)
		(fp_line
			(start 0.7874 -0.4064)
			(end 0.7874 0.4064)
			(stroke
				(width 0.1524)
				(type default)
			)
			(layer "F.SilkS")
		)
		(fp_line
			(start -0.67945 0.3048)
			(end -0.67945 -0.305054)
			(stroke
				(width 0.1)
				(type default)
			)
			(layer "F.Fab")
		)
		(fp_line
			(start -0.12065 0.3048)
			(end -0.67945 0.3048)
			(stroke
				(width 0.1)
				(type default)
			)
			(layer "F.Fab")
		)
		(fp_line
			(start 0.120396 0.3048)
			(end 0.120396 0.2794)
			(stroke
				(width 0.1)
				(type default)
			)
			(layer "F.Fab")
		)
		(fp_line
			(start 0.67945 0.3048)
			(end 0.120396 0.3048)
			(stroke
				(width 0.1)
				(type default)
			)
			(layer "F.Fab")
		)
		(fp_line
			(start -0.12065 0.2794)
			(end -0.12065 0.3048)
			(stroke
				(width 0.1)
				(type default)
			)
			(layer "F.Fab")
		)
		(fp_line
			(start 0.120396 0.2794)
			(end -0.12065 0.2794)
			(stroke
				(width 0.1)
				(type default)
			)
			(layer "F.Fab")
		)
		(fp_line
			(start -0.12065 -0.2794)
			(end 0.12065 -0.2794)
			(stroke
				(width 0.1)
				(type default)
			)
			(layer "F.Fab")
		)
		(fp_line
			(start 0.12065 -0.2794)
			(end 0.12065 -0.3048)
			(stroke
				(width 0.1)
				(type default)
			)
			(layer "F.Fab")
		)
		(fp_line
			(start 0.12065 -0.3048)
			(end 0.67945 -0.3048)
			(stroke
				(width 0.1)
				(type default)
			)
			(layer "F.Fab")
		)
		(fp_line
			(start 0.67945 -0.3048)
			(end 0.67945 0.3048)
			(stroke
				(width 0.1)
				(type default)
			)
			(layer "F.Fab")
		)
		(fp_line
			(start -0.67945 -0.305054)
			(end -0.12065 -0.305054)
			(stroke
				(width 0.1)
				(type default)
			)
			(layer "F.Fab")
		)
		(fp_line
			(start -0.12065 -0.305054)
			(end -0.12065 -0.2794)
			(stroke
				(width 0.1)
				(type default)
			)
			(layer "F.Fab")
		)
		(pad "1" smd circle
			(at -0.40005 0 270)
			(size 0 0)
			(layers "F.Cu" "F.Mask" "F.Paste")
			(net "P1V25_SERDES_VDDPLL_PEX1")
		)
		(pad "2" smd circle
			(at 0.40005 0 270)
			(size 0 0)
			(layers "F.Cu" "F.Mask" "F.Paste")
			(net "P1V25_SERDES_VDDPLL_PEX1_C8")
		)
	)
)
